(kicad_pcb
	(version 20241229)
	(generator "pcbnew")
	(generator_version "9.0")
	(general
		(thickness 1.6296)
		(legacy_teardrops no)
	)
	(paper "A3")
	(title_block
		(title "Thunderbolt to 10GbE adapter")
		(date "2026-04-21")
		(rev "1.1.0")
		(company "Antmicro Ltd")
		(comment 1 "www.antmicro.com")
		(comment 9 "footprints 483-487 of 703")
	)
	(layers
		(0 "F.Cu" signal)
		(4 "In1.Cu" signal)
		(6 "In2.Cu" signal)
		(8 "In3.Cu" signal)
		(10 "In4.Cu" signal)
		(12 "In5.Cu" signal)
		(14 "In6.Cu" signal)
		(2 "B.Cu" signal)
		(9 "F.Adhes" user "F.Adhesive")
		(11 "B.Adhes" user "B.Adhesive")
		(13 "F.Paste" user)
		(15 "B.Paste" user)
		(5 "F.SilkS" user "F.Silkscreen")
		(7 "B.SilkS" user "B.Silkscreen")
		(1 "F.Mask" user)
		(3 "B.Mask" user)
		(17 "Dwgs.User" user "User.Drawings")
		(19 "Cmts.User" user "User.Comments")
		(21 "Eco1.User" user "User.Eco1")
		(23 "Eco2.User" user "User.Eco2")
		(25 "Edge.Cuts" user)
		(27 "Margin" user)
		(31 "F.CrtYd" user "F.Courtyard")
		(29 "B.CrtYd" user "B.Courtyard")
		(35 "F.Fab" user)
		(33 "B.Fab" user)
	)
	(footprint "antmicro-footprints:R_0402_1005Metric"
		(layer "B.Cu")
		(at 136.500001 115.1 180)
		(descr "Resistor SMD 0402")
		(tags "resistor SMD 0402")
		(property "Reference" "R34"
			(at -19.525001 7.450001 0)
			(layer "B.SilkS")
			(effects
				(font
					(size 0.7 0.7)
					(thickness 0.15)
				)
				(justify mirror)
			)
		)
		(property "Value" "R_100k_0402"
			(at -1.011843 -1.772047 0)
			(layer "B.Fab")
			(effects
				(font
					(size 0.7 0.7)
					(thickness 0.15)
				)
				(justify left bottom mirror)
			)
		)
		(property "Datasheet" "https://www.bourns.com/docs/product-datasheets/cr.pdf"
			(at 0 0 0)
			(layer "B.Fab")
			(hide yes)
			(effects
				(font
					(size 1.27 1.27)
					(thickness 0.15)
				)
				(justify mirror)
			)
		)
		(property "Description" "SMD Chip Resistor, 100 kohm, ± 1%, 62.5 mW, 0402 [1005 Metric], Thick Film, General Purpose"
			(at 0 0 0)
			(layer "B.Fab")
			(hide yes)
			(effects
				(font
					(size 1.27 1.27)
					(thickness 0.15)
				)
				(justify mirror)
			)
		)
		(property "MPN" "CR0402-FX-1003GLF"
			(at 0 0 180)
			(unlocked yes)
			(layer "B.Fab")
			(hide yes)
			(effects
				(font
					(size 1 1)
					(thickness 0.15)
				)
				(justify mirror)
			)
		)
		(property "Manufacturer" "Bourns"
			(at 0 0 180)
			(unlocked yes)
			(layer "B.Fab")
			(hide yes)
			(effects
				(font
					(size 1 1)
					(thickness 0.15)
				)
				(justify mirror)
			)
		)
		(property "License" "Apache-2.0"
			(at 0 0 180)
			(unlocked yes)
			(layer "B.Fab")
			(hide yes)
			(effects
				(font
					(size 1 1)
					(thickness 0.15)
				)
				(justify mirror)
			)
		)
		(property "Val" "100k"
			(at 0 0 180)
			(unlocked yes)
			(layer "B.Fab")
			(hide yes)
			(effects
				(font
					(size 1 1)
					(thickness 0.15)
				)
				(justify mirror)
			)
		)
		(property "Tolerance" "1%"
			(at 0 0 180)
			(unlocked yes)
			(layer "B.Fab")
			(hide yes)
			(effects
				(font
					(size 1 1)
					(thickness 0.15)
				)
				(justify mirror)
			)
		)
		(property "Author" "Antmicro"
			(at 0 0 180)
			(unlocked yes)
			(layer "B.Fab")
			(hide yes)
			(effects
				(font
					(size 1 1)
					(thickness 0.15)
				)
				(justify mirror)
			)
		)
		(sheetname "/TB Controller/")
		(sheetfile "tb.kicad_sch")
		(attr smd)
		(fp_rect
			(start -0.925 0.47)
			(end 0.925 -0.47)
			(stroke
				(width 0.05)
				(type default)
			)
			(fill no)
			(layer "B.CrtYd")
		)
		(fp_rect
			(start -0.5 0.25)
			(end 0.5 -0.25)
			(stroke
				(width 0.15)
				(type solid)
			)
			(fill no)
			(layer "B.Fab")
		)
		(fp_text user "License: Apache-2.0"
			(at -0.95 -5.169 0)
			(layer "B.Fab")
			(effects
				(font
					(size 0.7 0.7)
					(thickness 0.15)
				)
				(justify left bottom mirror)
			)
		)
		(fp_text user "Author: Antmicro"
			(at -0.95 -4.169 0)
			(layer "B.Fab")
			(effects
				(font
					(size 0.7 0.7)
					(thickness 0.15)
				)
				(justify left bottom mirror)
			)
		)
		(fp_text user "${REFERENCE}"
			(at -0.95 -3.168 0)
			(layer "B.Fab")
			(effects
				(font
					(size 0.7 0.7)
					(thickness 0.15)
				)
				(justify left bottom mirror)
			)
		)
		(pad "1" smd roundrect
			(at -0.48 0 180)
			(size 0.59 0.64)
			(layers "B.Cu" "B.Mask" "B.Paste")
			(roundrect_rratio 0.25)
			(net 23 "GND")
			(pintype "passive")
		)
		(pad "2" smd roundrect
			(at 0.48 0 180)
			(size 0.59 0.64)
			(layers "B.Cu" "B.Mask" "B.Paste")
			(roundrect_rratio 0.25)
			(net 217 "Net-(U4C-DPSNK0_HPD)")
			(pintype "passive")
		)
	)
	(footprint "antmicro-footprints:R_0402_1005Metric"
		(layer "B.Cu")
		(at 151.131866 70.035117 90)
		(descr "Resistor SMD 0402")
		(tags "resistor SMD 0402")
		(property "Reference" "R192"
			(at -9.464883 19.468134 270)
			(layer "B.SilkS")
			(effects
				(font
					(size 0.7 0.7)
					(thickness 0.15)
				)
				(justify mirror)
			)
		)
		(property "Value" "R_3k3_0402"
			(at -1.011843 -1.772047 270)
			(layer "B.Fab")
			(effects
				(font
					(size 0.7 0.7)
					(thickness 0.15)
				)
				(justify left bottom mirror)
			)
		)
		(property "Datasheet" "https://www.bourns.com/docs/product-datasheets/cr.pdf"
			(at 0 0 270)
			(layer "B.Fab")
			(hide yes)
			(effects
				(font
					(size 1.27 1.27)
					(thickness 0.15)
				)
				(justify mirror)
			)
		)
		(property "Description" "SMD Chip Resistor, 3.3 kohm, ± 1%, 63 mW, 0402 [1005 Metric], Thick Film, General Purpose"
			(at 0 0 270)
			(layer "B.Fab")
			(hide yes)
			(effects
				(font
					(size 1.27 1.27)
					(thickness 0.15)
				)
				(justify mirror)
			)
		)
		(property "MPN" "CR0402-FX-3301GLF"
			(at 0 0 90)
			(unlocked yes)
			(layer "B.Fab")
			(hide yes)
			(effects
				(font
					(size 1 1)
					(thickness 0.15)
				)
				(justify mirror)
			)
		)
		(property "Manufacturer" "Bourns"
			(at 0 0 90)
			(unlocked yes)
			(layer "B.Fab")
			(hide yes)
			(effects
				(font
					(size 1 1)
					(thickness 0.15)
				)
				(justify mirror)
			)
		)
		(property "License" "Apache-2.0"
			(at 0 0 90)
			(unlocked yes)
			(layer "B.Fab")
			(hide yes)
			(effects
				(font
					(size 1 1)
					(thickness 0.15)
				)
				(justify mirror)
			)
		)
		(property "Author" "Antmicro"
			(at 0 0 90)
			(unlocked yes)
			(layer "B.Fab")
			(hide yes)
			(effects
				(font
					(size 1 1)
					(thickness 0.15)
				)
				(justify mirror)
			)
		)
		(property "Val" "3k3"
			(at 0 0 90)
			(unlocked yes)
			(layer "B.Fab")
			(hide yes)
			(effects
				(font
					(size 1 1)
					(thickness 0.15)
				)
				(justify mirror)
			)
		)
		(property "Tolerance" "1%"
			(at 0 0 90)
			(unlocked yes)
			(layer "B.Fab")
			(hide yes)
			(effects
				(font
					(size 1 1)
					(thickness 0.15)
				)
				(justify mirror)
			)
		)
		(sheetname "/X710-AT2 10GbE/")
		(sheetfile "x710-at2-10gbe.kicad_sch")
		(attr smd)
		(fp_rect
			(start -0.925 0.47)
			(end 0.925 -0.47)
			(stroke
				(width 0.05)
				(type default)
			)
			(fill no)
			(layer "B.CrtYd")
		)
		(fp_rect
			(start -0.5 0.25)
			(end 0.5 -0.25)
			(stroke
				(width 0.15)
				(type solid)
			)
			(fill no)
			(layer "B.Fab")
		)
		(fp_text user "Author: Antmicro"
			(at -0.95 -4.169 270)
			(layer "B.Fab")
			(effects
				(font
					(size 0.7 0.7)
					(thickness 0.15)
				)
				(justify left bottom mirror)
			)
		)
		(fp_text user "${REFERENCE}"
			(at -0.95 -3.168 270)
			(layer "B.Fab")
			(effects
				(font
					(size 0.7 0.7)
					(thickness 0.15)
				)
				(justify left bottom mirror)
			)
		)
		(fp_text user "License: Apache-2.0"
			(at -0.95 -5.169 270)
			(layer "B.Fab")
			(effects
				(font
					(size 0.7 0.7)
					(thickness 0.15)
				)
				(justify left bottom mirror)
			)
		)
		(pad "1" smd roundrect
			(at -0.48 0 90)
			(size 0.59 0.64)
			(layers "B.Cu" "B.Mask" "B.Paste")
			(roundrect_rratio 0.25)
			(net 72 "/X710-AT2 10GbE/MDC2_SCL2")
			(pintype "passive")
		)
		(pad "2" smd roundrect
			(at 0.48 0 90)
			(size 0.59 0.64)
			(layers "B.Cu" "B.Mask" "B.Paste")
			(roundrect_rratio 0.25)
			(net 7 "+3V3")
			(pintype "passive")
		)
	)
	(footprint "antmicro-footprints:C_0402_1005Metric"
		(layer "B.Cu")
		(at 171.58 146.66 -90)
		(descr "Capacitor SMD 0402")
		(tags "capacitor SMD 0402")
		(property "Reference" "C307"
			(at 1.09 -0.42 90)
			(layer "B.SilkS")
			(effects
				(font
					(size 0.7 0.7)
					(thickness 0.15)
				)
				(justify left bottom mirror)
			)
		)
		(property "Value" "C_470p_0402"
			(at -1.022927 -2.155213 90)
			(layer "B.Fab")
			(effects
				(font
					(size 0.7 0.7)
					(thickness 0.15)
				)
				(justify left bottom mirror)
			)
		)
		(property "Datasheet" "https://www.passivecomponent.com/wp-content/uploads/datasheet/WTC_MLCC_General_Purpose.pdf"
			(at 0 0 90)
			(layer "B.Fab")
			(hide yes)
			(effects
				(font
					(size 1.27 1.27)
					(thickness 0.15)
				)
				(justify mirror)
			)
		)
		(property "Description" "SMD Multilayer Ceramic Capacitor, General Purpose, 470 pF, 25 V, 0402 [1005 Metric], ± 10%, X7R"
			(at 0 0 90)
			(layer "B.Fab")
			(hide yes)
			(effects
				(font
					(size 1.27 1.27)
					(thickness 0.15)
				)
				(justify mirror)
			)
		)
		(property "MPN" "0402B471K250CT"
			(at 0 0 270)
			(unlocked yes)
			(layer "B.Fab")
			(hide yes)
			(effects
				(font
					(size 1 1)
					(thickness 0.15)
				)
				(justify mirror)
			)
		)
		(property "Manufacturer" "Walsin"
			(at 0 0 270)
			(unlocked yes)
			(layer "B.Fab")
			(hide yes)
			(effects
				(font
					(size 1 1)
					(thickness 0.15)
				)
				(justify mirror)
			)
		)
		(property "License" "Apache-2.0"
			(at 0 0 270)
			(unlocked yes)
			(layer "B.Fab")
			(hide yes)
			(effects
				(font
					(size 1 1)
					(thickness 0.15)
				)
				(justify mirror)
			)
		)
		(property "Author" "Antmicro"
			(at 0 0 270)
			(unlocked yes)
			(layer "B.Fab")
			(hide yes)
			(effects
				(font
					(size 1 1)
					(thickness 0.15)
				)
				(justify mirror)
			)
		)
		(property "Val" "470p"
			(at 0 0 270)
			(unlocked yes)
			(layer "B.Fab")
			(hide yes)
			(effects
				(font
					(size 1 1)
					(thickness 0.15)
				)
				(justify mirror)
			)
		)
		(property "Voltage" "25V"
			(at 0 0 270)
			(unlocked yes)
			(layer "B.Fab")
			(hide yes)
			(effects
				(font
					(size 1 1)
					(thickness 0.15)
				)
				(justify mirror)
			)
		)
		(property "Dielectric" "X7R"
			(at 0 0 270)
			(unlocked yes)
			(layer "B.Fab")
			(hide yes)
			(effects
				(font
					(size 1 1)
					(thickness 0.15)
				)
				(justify mirror)
			)
		)
		(sheetname "/2xRJ45/")
		(sheetfile "2xrj45.kicad_sch")
		(attr smd)
		(fp_rect
			(start -0.925 0.47)
			(end 0.925 -0.47)
			(stroke
				(width 0.05)
				(type default)
			)
			(fill no)
			(layer "B.CrtYd")
		)
		(fp_line
			(start -0.494 0.25)
			(end 0.504 0.25)
			(stroke
				(width 0.15)
				(type solid)
			)
			(layer "B.Fab")
		)
		(fp_line
			(start 0.504 0.25)
			(end 0.504 -0.248)
			(stroke
				(width 0.15)
				(type solid)
			)
			(layer "B.Fab")
		)
		(fp_line
			(start -0.494 -0.248)
			(end -0.494 0.25)
			(stroke
				(width 0.15)
				(type solid)
			)
			(layer "B.Fab")
		)
		(fp_line
			(start 0.504 -0.248)
			(end -0.494 -0.248)
			(stroke
				(width 0.15)
				(type solid)
			)
			(layer "B.Fab")
		)
		(fp_text user "Author: Antmicro"
			(at -0.939 -3.399 90)
			(layer "B.Fab")
			(effects
				(font
					(size 0.7 0.7)
					(thickness 0.15)
				)
				(justify left bottom mirror)
			)
		)
		(fp_text user "${REFERENCE}"
			(at -0.939 -4.599 90)
			(layer "B.Fab")
			(effects
				(font
					(size 0.7 0.7)
					(thickness 0.15)
				)
				(justify left bottom mirror)
			)
		)
		(fp_text user "License: Apache-2.0"
			(at -0.939 -5.799 90)
			(layer "B.Fab")
			(effects
				(font
					(size 0.7 0.7)
					(thickness 0.15)
				)
				(justify left bottom mirror)
			)
		)
		(pad "1" smd roundrect
			(at -0.48 0 270)
			(size 0.59 0.64)
			(layers "B.Cu" "B.Mask" "B.Paste")
			(roundrect_rratio 0.25)
			(net 23 "GND")
			(pintype "passive")
		)
		(pad "2" smd roundrect
			(at 0.48 0 270)
			(size 0.59 0.64)
			(layers "B.Cu" "B.Mask" "B.Paste")
			(roundrect_rratio 0.25)
			(net 411 "Net-(J4-LED_GRN-)")
			(pintype "passive")
		)
	)
	(footprint "antmicro-footprints:C_0402_1005Metric"
		(layer "B.Cu")
		(at 139.4 105 90)
		(descr "Capacitor SMD 0402")
		(tags "capacitor SMD 0402")
		(property "Reference" "C150"
			(at 1.4 -0.6 270)
			(layer "B.SilkS")
			(effects
				(font
					(size 0.7 0.7)
					(thickness 0.15)
				)
				(justify left bottom mirror)
			)
		)
		(property "Value" "C_100n_0402"
			(at -1.022927 -2.155213 270)
			(layer "B.Fab")
			(effects
				(font
					(size 0.7 0.7)
					(thickness 0.15)
				)
				(justify left bottom mirror)
			)
		)
		(property "Datasheet" "https://www.murata.com/products/productdetail?partno=GRM155R61H104KE14%23"
			(at 0 0 270)
			(layer "B.Fab")
			(hide yes)
			(effects
				(font
					(size 1.27 1.27)
					(thickness 0.15)
				)
				(justify mirror)
			)
		)
		(property "Description" "SMD Multilayer Ceramic Capacitor, 0.1 µF, 50 V, 0402 [1005 Metric], ± 10%, X5R, GRM Series"
			(at 0 0 270)
			(layer "B.Fab")
			(hide yes)
			(effects
				(font
					(size 1.27 1.27)
					(thickness 0.15)
				)
				(justify mirror)
			)
		)
		(property "MPN" "GRM155R61H104KE14D"
			(at 0 0 90)
			(unlocked yes)
			(layer "B.Fab")
			(hide yes)
			(effects
				(font
					(size 1 1)
					(thickness 0.15)
				)
				(justify mirror)
			)
		)
		(property "Manufacturer" "Murata"
			(at 0 0 90)
			(unlocked yes)
			(layer "B.Fab")
			(hide yes)
			(effects
				(font
					(size 1 1)
					(thickness 0.15)
				)
				(justify mirror)
			)
		)
		(property "License" "Apache-2.0"
			(at 0 0 90)
			(unlocked yes)
			(layer "B.Fab")
			(hide yes)
			(effects
				(font
					(size 1 1)
					(thickness 0.15)
				)
				(justify mirror)
			)
		)
		(property "Author" "Antmicro"
			(at 0 0 90)
			(unlocked yes)
			(layer "B.Fab")
			(hide yes)
			(effects
				(font
					(size 1 1)
					(thickness 0.15)
				)
				(justify mirror)
			)
		)
		(property "Val" "100n"
			(at 0 0 90)
			(unlocked yes)
			(layer "B.Fab")
			(hide yes)
			(effects
				(font
					(size 1 1)
					(thickness 0.15)
				)
				(justify mirror)
			)
		)
		(property "Voltage" "50V"
			(at 0 0 90)
			(unlocked yes)
			(layer "B.Fab")
			(hide yes)
			(effects
				(font
					(size 1 1)
					(thickness 0.15)
				)
				(justify mirror)
			)
		)
		(property "Dielectric" "X5R"
			(at 0 0 90)
			(unlocked yes)
			(layer "B.Fab")
			(hide yes)
			(effects
				(font
					(size 1 1)
					(thickness 0.15)
				)
				(justify mirror)
			)
		)
		(sheetname "/X710 DCDC converters/")
		(sheetfile "DCDC_converters_X710.kicad_sch")
		(attr smd)
		(fp_rect
			(start -0.925 0.47)
			(end 0.925 -0.47)
			(stroke
				(width 0.05)
				(type default)
			)
			(fill no)
			(layer "B.CrtYd")
		)
		(fp_line
			(start 0.504 -0.248)
			(end -0.494 -0.248)
			(stroke
				(width 0.15)
				(type solid)
			)
			(layer "B.Fab")
		)
		(fp_line
			(start -0.494 -0.248)
			(end -0.494 0.25)
			(stroke
				(width 0.15)
				(type solid)
			)
			(layer "B.Fab")
		)
		(fp_line
			(start 0.504 0.25)
			(end 0.504 -0.248)
			(stroke
				(width 0.15)
				(type solid)
			)
			(layer "B.Fab")
		)
		(fp_line
			(start -0.494 0.25)
			(end 0.504 0.25)
			(stroke
				(width 0.15)
				(type solid)
			)
			(layer "B.Fab")
		)
		(fp_text user "Author: Antmicro"
			(at -0.939 -3.399 270)
			(layer "B.Fab")
			(effects
				(font
					(size 0.7 0.7)
					(thickness 0.15)
				)
				(justify left bottom mirror)
			)
		)
		(fp_text user "License: Apache-2.0"
			(at -0.939 -5.799 270)
			(layer "B.Fab")
			(effects
				(font
					(size 0.7 0.7)
					(thickness 0.15)
				)
				(justify left bottom mirror)
			)
		)
		(fp_text user "${REFERENCE}"
			(at -0.939 -4.599 270)
			(layer "B.Fab")
			(effects
				(font
					(size 0.7 0.7)
					(thickness 0.15)
				)
				(justify left bottom mirror)
			)
		)
		(pad "1" smd roundrect
			(at -0.48 0 90)
			(size 0.59 0.64)
			(layers "B.Cu" "B.Mask" "B.Paste")
			(roundrect_rratio 0.25)
			(net 23 "GND")
			(pintype "passive")
		)
		(pad "2" smd roundrect
			(at 0.48 0 90)
			(size 0.59 0.64)
			(layers "B.Cu" "B.Mask" "B.Paste")
			(roundrect_rratio 0.25)
			(net 335 "/X710 DCDC converters/+VCCD_OUT")
			(pintype "passive")
		)
	)
	(footprint "antmicro-footprints:R_0402_1005Metric"
		(layer "B.Cu")
		(at 153.131866 70.035117 90)
		(descr "Resistor SMD 0402")
		(tags "resistor SMD 0402")
		(property "Reference" "R190"
			(at -9.464883 19.468134 270)
			(layer "B.SilkS")
			(effects
				(font
					(size 0.7 0.7)
					(thickness 0.15)
				)
				(justify mirror)
			)
		)
		(property "Value" "R_3k3_0402"
			(at -1.011843 -1.772047 270)
			(layer "B.Fab")
			(effects
				(font
					(size 0.7 0.7)
					(thickness 0.15)
				)
				(justify left bottom mirror)
			)
		)
		(property "Datasheet" "https://www.bourns.com/docs/product-datasheets/cr.pdf"
			(at 0 0 270)
			(layer "B.Fab")
			(hide yes)
			(effects
				(font
					(size 1.27 1.27)
					(thickness 0.15)
				)
				(justify mirror)
			)
		)
		(property "Description" "SMD Chip Resistor, 3.3 kohm, ± 1%, 63 mW, 0402 [1005 Metric], Thick Film, General Purpose"
			(at 0 0 270)
			(layer "B.Fab")
			(hide yes)
			(effects
				(font
					(size 1.27 1.27)
					(thickness 0.15)
				)
				(justify mirror)
			)
		)
		(property "MPN" "CR0402-FX-3301GLF"
			(at 0 0 90)
			(unlocked yes)
			(layer "B.Fab")
			(hide yes)
			(effects
				(font
					(size 1 1)
					(thickness 0.15)
				)
				(justify mirror)
			)
		)
		(property "Manufacturer" "Bourns"
			(at 0 0 90)
			(unlocked yes)
			(layer "B.Fab")
			(hide yes)
			(effects
				(font
					(size 1 1)
					(thickness 0.15)
				)
				(justify mirror)
			)
		)
		(property "License" "Apache-2.0"
			(at 0 0 90)
			(unlocked yes)
			(layer "B.Fab")
			(hide yes)
			(effects
				(font
					(size 1 1)
					(thickness 0.15)
				)
				(justify mirror)
			)
		)
		(property "Author" "Antmicro"
			(at 0 0 90)
			(unlocked yes)
			(layer "B.Fab")
			(hide yes)
			(effects
				(font
					(size 1 1)
					(thickness 0.15)
				)
				(justify mirror)
			)
		)
		(property "Val" "3k3"
			(at 0 0 90)
			(unlocked yes)
			(layer "B.Fab")
			(hide yes)
			(effects
				(font
					(size 1 1)
					(thickness 0.15)
				)
				(justify mirror)
			)
		)
		(property "Tolerance" "1%"
			(at 0 0 90)
			(unlocked yes)
			(layer "B.Fab")
			(hide yes)
			(effects
				(font
					(size 1 1)
					(thickness 0.15)
				)
				(justify mirror)
			)
		)
		(sheetname "/X710-AT2 10GbE/")
		(sheetfile "x710-at2-10gbe.kicad_sch")
		(attr smd)
		(fp_rect
			(start -0.925 0.47)
			(end 0.925 -0.47)
			(stroke
				(width 0.05)
				(type default)
			)
			(fill no)
			(layer "B.CrtYd")
		)
		(fp_rect
			(start -0.5 0.25)
			(end 0.5 -0.25)
			(stroke
				(width 0.15)
				(type solid)
			)
			(fill no)
			(layer "B.Fab")
		)
		(fp_text user "License: Apache-2.0"
			(at -0.95 -5.169 270)
			(layer "B.Fab")
			(effects
				(font
					(size 0.7 0.7)
					(thickness 0.15)
				)
				(justify left bottom mirror)
			)
		)
		(fp_text user "${REFERENCE}"
			(at -0.95 -3.168 270)
			(layer "B.Fab")
			(effects
				(font
					(size 0.7 0.7)
					(thickness 0.15)
				)
				(justify left bottom mirror)
			)
		)
		(fp_text user "Author: Antmicro"
			(at -0.95 -4.169 270)
			(layer "B.Fab")
			(effects
				(font
					(size 0.7 0.7)
					(thickness 0.15)
				)
				(justify left bottom mirror)
			)
		)
		(pad "1" smd roundrect
			(at -0.48 0 90)
			(size 0.59 0.64)
			(layers "B.Cu" "B.Mask" "B.Paste")
			(roundrect_rratio 0.25)
			(net 71 "/X710-AT2 10GbE/MDIO3_SDA3")
			(pintype "passive")
		)
		(pad "2" smd roundrect
			(at 0.48 0 90)
			(size 0.59 0.64)
			(layers "B.Cu" "B.Mask" "B.Paste")
			(roundrect_rratio 0.25)
			(net 7 "+3V3")
			(pintype "passive")
		)
	)
)
